(kicad_pcb
	(version 20260206)
	(generator "pcbnew")
	(generator_version "10.0")
	(general
		(thickness 1.6)
		(legacy_teardrops no)
	)
	(paper "A4")
	(title_block
		(title "Bryce Canyon_IOM_IOC_16318-2_OCP.brd")
		(comment 1 "Bryce Canyon / footprints 715-721 of 1605")
	)
	(layers
		(0 "F.Cu" signal "TOP")
		(4 "In1.Cu" signal "L2GND")
		(6 "In2.Cu" signal "L3")
		(8 "In3.Cu" signal "L4VCC")
		(10 "In4.Cu" signal "L5VCC")
		(12 "In5.Cu" signal "L6")
		(14 "In6.Cu" signal "L7GND")
		(2 "B.Cu" signal "BOTTOM")
		(9 "F.Adhes" user "F.Adhesive")
		(11 "B.Adhes" user "B.Adhesive")
		(13 "F.Paste" user "Package Geometry/Pastemask Top")
		(15 "B.Paste" user "Package Geometry/Pastemask Bottom")
		(5 "F.SilkS" user "Ref Des/Silkscreen Top")
		(7 "B.SilkS" user "Ref Des/Silkscreen Bottom")
		(1 "F.Mask" user "Board Geometry/Soldermask Top")
		(3 "B.Mask" user "Board Geometry/Soldermask Bottom")
		(17 "Dwgs.User" user "User.Drawings")
		(19 "Cmts.User" user "User.Comments")
		(21 "Eco1.User" user "User.Eco1")
		(23 "Eco2.User" user "User.Eco2")
		(25 "Edge.Cuts" user "Board Geometry/Outline")
		(27 "Margin" user)
		(31 "F.CrtYd" user "Package Geometry/Place Bound Top")
		(29 "B.CrtYd" user "Package Geometry/Place Bound Bottom")
		(35 "F.Fab" user "Ref Des/Assembly Top")
		(33 "B.Fab" user "Ref Des/Assembly Bottom")
	)
	(footprint ""
		(layer "F.Cu")
		(at 17.7546 -129.1082 180)
		(property "Reference" "R220"
			(at 0 0 180)
			(layer "F.SilkS")
			(hide yes)
			(effects
				(font
					(size 1.27 1.27)
				)
			)
		)
		(property "Value" "120R2F-GP"
			(at 0.064008 -3.993896 180)
			(unlocked yes)
			(layer "F.Fab")
			(hide yes)
			(effects
				(font
					(size 1.016 1.016)
					(thickness 0.1524)
				)
			)
		)
		(property "Device Type" "R402H16"
			(at 0.064008 -5.517896 180)
			(unlocked yes)
			(layer "F.Fab")
			(hide yes)
			(effects
				(font
					(size 1.016 1.016)
					(thickness 0.1524)
				)
			)
		)
		(duplicate_pad_numbers_are_jumpers no)
		(fp_line
			(start 0.508 -0.9398)
			(end -0.508 -0.9398)
			(stroke
				(width 0.1524)
				(type default)
			)
			(layer "F.SilkS")
		)
		(fp_line
			(start -0.508 -0.9398)
			(end -0.508 0.9398)
			(stroke
				(width 0.1524)
				(type default)
			)
			(layer "F.SilkS")
		)
		(fp_rect
			(start -0.508 0.9398)
			(end 0.508 -0.9398)
			(stroke
				(width 0)
				(type default)
			)
			(fill no)
			(layer "F.CrtYd")
		)
		(fp_rect
			(start -0.508 0.9398)
			(end 0.508 -0.9398)
			(stroke
				(width 0)
				(type default)
			)
			(fill no)
			(layer "F.Fab")
		)
		(pad "1" smd custom
			(at 0 -0.4445 180)
			(size 0.1397 0.1397)
			(layers "F.Cu" "F.Mask" "F.Paste")
			(net "GND")
			(options
				(clearance outline)
				(anchor circle)
			)
			(primitives
				(gr_poly
					(pts
						(arc
							(start -0.1778 -0.2794)
							(mid -0.249642 -0.249642)
							(end -0.2794 -0.1778)
						)
						(arc
							(start -0.2794 0.1778)
							(mid -0.249642 0.249642)
							(end -0.1778 0.2794)
						)
						(arc
							(start 0.1778 0.2794)
							(mid 0.249642 0.249642)
							(end 0.2794 0.1778)
						)
						(arc
							(start 0.2794 -0.1778)
							(mid 0.249642 -0.249642)
							(end 0.1778 -0.2794)
						)
					)
					(width 0)
					(fill yes)
				)
			)
		)
		(pad "2" smd custom
			(at 0 0.4445 180)
			(size 0.1397 0.1397)
			(layers "F.Cu" "F.Mask" "F.Paste")
			(net "DDR4_ACT")
			(options
				(clearance outline)
				(anchor circle)
			)
			(primitives
				(gr_poly
					(pts
						(arc
							(start -0.1778 -0.2794)
							(mid -0.249642 -0.249642)
							(end -0.2794 -0.1778)
						)
						(arc
							(start -0.2794 0.1778)
							(mid -0.249642 0.249642)
							(end -0.1778 0.2794)
						)
						(arc
							(start 0.1778 0.2794)
							(mid 0.249642 0.249642)
							(end 0.2794 0.1778)
						)
						(arc
							(start 0.2794 -0.1778)
							(mid 0.249642 -0.249642)
							(end 0.1778 -0.2794)
						)
					)
					(width 0)
					(fill yes)
				)
			)
		)
	)
	(footprint ""
		(layer "F.Cu")
		(at 92.548456 -161.52368 90)
		(property "Reference" "R27"
			(at 0 0 90)
			(layer "F.SilkS")
			(hide yes)
			(effects
				(font
					(size 1.27 1.27)
				)
			)
		)
		(property "Value" "1MR2F-GP"
			(at 0.064008 -3.993896 90)
			(unlocked yes)
			(layer "F.Fab")
			(hide yes)
			(effects
				(font
					(size 1.016 1.016)
					(thickness 0.1524)
				)
			)
		)
		(property "Device Type" "R402H16"
			(at 0.064008 -5.517896 90)
			(unlocked yes)
			(layer "F.Fab")
			(hide yes)
			(effects
				(font
					(size 1.016 1.016)
					(thickness 0.1524)
				)
			)
		)
		(duplicate_pad_numbers_are_jumpers no)
		(fp_line
			(start 0.508 -0.9398)
			(end -0.508 -0.9398)
			(stroke
				(width 0.1524)
				(type default)
			)
			(layer "F.SilkS")
		)
		(fp_line
			(start -0.508 -0.9398)
			(end -0.508 0.9398)
			(stroke
				(width 0.1524)
				(type default)
			)
			(layer "F.SilkS")
		)
		(fp_rect
			(start -0.508 0.9398)
			(end 0.508 -0.9398)
			(stroke
				(width 0)
				(type default)
			)
			(fill no)
			(layer "F.CrtYd")
		)
		(fp_rect
			(start -0.508 0.9398)
			(end 0.508 -0.9398)
			(stroke
				(width 0)
				(type default)
			)
			(fill no)
			(layer "F.Fab")
		)
		(pad "1" smd custom
			(at 0 -0.4445 90)
			(size 0.1397 0.1397)
			(layers "F.Cu" "F.Mask" "F.Paste")
			(net "USB_HUB_XTAL_IN")
			(options
				(clearance outline)
				(anchor circle)
			)
			(primitives
				(gr_poly
					(pts
						(arc
							(start -0.1778 -0.2794)
							(mid -0.249642 -0.249642)
							(end -0.2794 -0.1778)
						)
						(arc
							(start -0.2794 0.1778)
							(mid -0.249642 0.249642)
							(end -0.1778 0.2794)
						)
						(arc
							(start 0.1778 0.2794)
							(mid 0.249642 0.249642)
							(end 0.2794 0.1778)
						)
						(arc
							(start 0.2794 -0.1778)
							(mid 0.249642 -0.249642)
							(end 0.1778 -0.2794)
						)
					)
					(width 0)
					(fill yes)
				)
			)
		)
		(pad "2" smd custom
			(at 0 0.4445 90)
			(size 0.1397 0.1397)
			(layers "F.Cu" "F.Mask" "F.Paste")
			(net "USB_HUB_XTAL_OUT")
			(options
				(clearance outline)
				(anchor circle)
			)
			(primitives
				(gr_poly
					(pts
						(arc
							(start -0.1778 -0.2794)
							(mid -0.249642 -0.249642)
							(end -0.2794 -0.1778)
						)
						(arc
							(start -0.2794 0.1778)
							(mid -0.249642 0.249642)
							(end -0.1778 0.2794)
						)
						(arc
							(start 0.1778 0.2794)
							(mid 0.249642 0.249642)
							(end 0.2794 0.1778)
						)
						(arc
							(start 0.2794 -0.1778)
							(mid 0.249642 -0.249642)
							(end 0.1778 -0.2794)
						)
					)
					(width 0)
					(fill yes)
				)
			)
		)
	)
	(footprint ""
		(layer "F.Cu")
		(at 217.678 -102.8954)
		(property "Reference" "R600"
			(at 0 0 0)
			(layer "F.SilkS")
			(hide yes)
			(effects
				(font
					(size 1.27 1.27)
				)
			)
		)
		(property "Value" "4K7R2F-GP"
			(at 0.064008 -3.993896 0)
			(unlocked yes)
			(layer "F.Fab")
			(hide yes)
			(effects
				(font
					(size 1.016 1.016)
					(thickness 0.1524)
				)
			)
		)
		(property "Device Type" "R402H16"
			(at 0.064008 -5.517896 0)
			(unlocked yes)
			(layer "F.Fab")
			(hide yes)
			(effects
				(font
					(size 1.016 1.016)
					(thickness 0.1524)
				)
			)
		)
		(duplicate_pad_numbers_are_jumpers no)
		(fp_line
			(start -0.508 -0.9398)
			(end -0.508 0.9398)
			(stroke
				(width 0.1524)
				(type default)
			)
			(layer "F.SilkS")
		)
		(fp_line
			(start 0.508 -0.9398)
			(end -0.508 -0.9398)
			(stroke
				(width 0.1524)
				(type default)
			)
			(layer "F.SilkS")
		)
		(fp_rect
			(start -0.508 0.9398)
			(end 0.508 -0.9398)
			(stroke
				(width 0)
				(type default)
			)
			(fill no)
			(layer "F.CrtYd")
		)
		(fp_rect
			(start -0.508 0.9398)
			(end 0.508 -0.9398)
			(stroke
				(width 0)
				(type default)
			)
			(fill no)
			(layer "F.Fab")
		)
		(pad "1" smd custom
			(at 0 -0.4445)
			(size 0.1397 0.1397)
			(layers "F.Cu" "F.Mask" "F.Paste")
			(net "P1V8")
			(options
				(clearance outline)
				(anchor circle)
			)
			(primitives
				(gr_poly
					(pts
						(arc
							(start -0.1778 -0.2794)
							(mid -0.249642 -0.249642)
							(end -0.2794 -0.1778)
						)
						(arc
							(start -0.2794 0.1778)
							(mid -0.249642 0.249642)
							(end -0.1778 0.2794)
						)
						(arc
							(start 0.1778 0.2794)
							(mid 0.249642 0.249642)
							(end 0.2794 0.1778)
						)
						(arc
							(start 0.2794 -0.1778)
							(mid 0.249642 -0.249642)
							(end 0.1778 -0.2794)
						)
					)
					(width 0)
					(fill yes)
				)
			)
		)
		(pad "2" smd custom
			(at 0 0.4445)
			(size 0.1397 0.1397)
			(layers "F.Cu" "F.Mask" "F.Paste")
			(net "IOC_EEPROM_A2")
			(options
				(clearance outline)
				(anchor circle)
			)
			(primitives
				(gr_poly
					(pts
						(arc
							(start -0.1778 -0.2794)
							(mid -0.249642 -0.249642)
							(end -0.2794 -0.1778)
						)
						(arc
							(start -0.2794 0.1778)
							(mid -0.249642 0.249642)
							(end -0.1778 0.2794)
						)
						(arc
							(start 0.1778 0.2794)
							(mid 0.249642 0.249642)
							(end 0.2794 0.1778)
						)
						(arc
							(start 0.2794 -0.1778)
							(mid 0.249642 -0.249642)
							(end 0.1778 -0.2794)
						)
					)
					(width 0)
					(fill yes)
				)
			)
		)
	)
	(footprint ""
		(layer "F.Cu")
		(at 31.673038 -152.888442 90)
		(property "Reference" "R701"
			(at 0 0 90)
			(layer "F.SilkS")
			(hide yes)
			(effects
				(font
					(size 1.27 1.27)
				)
			)
		)
		(property "Value" "4K7R2F-GP"
			(at 0.064008 -3.993896 90)
			(unlocked yes)
			(layer "F.Fab")
			(hide yes)
			(effects
				(font
					(size 1.016 1.016)
					(thickness 0.1524)
				)
			)
		)
		(property "Device Type" "R402H16"
			(at 0.064008 -5.517896 90)
			(unlocked yes)
			(layer "F.Fab")
			(hide yes)
			(effects
				(font
					(size 1.016 1.016)
					(thickness 0.1524)
				)
			)
		)
		(duplicate_pad_numbers_are_jumpers no)
		(fp_line
			(start 0.508 -0.9398)
			(end -0.508 -0.9398)
			(stroke
				(width 0.1524)
				(type default)
			)
			(layer "F.SilkS")
		)
		(fp_line
			(start -0.508 -0.9398)
			(end -0.508 0.9398)
			(stroke
				(width 0.1524)
				(type default)
			)
			(layer "F.SilkS")
		)
		(fp_rect
			(start -0.508 0.9398)
			(end 0.508 -0.9398)
			(stroke
				(width 0)
				(type default)
			)
			(fill no)
			(layer "F.CrtYd")
		)
		(fp_rect
			(start -0.508 0.9398)
			(end 0.508 -0.9398)
			(stroke
				(width 0)
				(type default)
			)
			(fill no)
			(layer "F.Fab")
		)
		(pad "1" smd custom
			(at 0 -0.4445 90)
			(size 0.1397 0.1397)
			(layers "F.Cu" "F.Mask" "F.Paste")
			(net "P3V3_STBY")
			(options
				(clearance outline)
				(anchor circle)
			)
			(primitives
				(gr_poly
					(pts
						(arc
							(start -0.1778 -0.2794)
							(mid -0.249642 -0.249642)
							(end -0.2794 -0.1778)
						)
						(arc
							(start -0.2794 0.1778)
							(mid -0.249642 0.249642)
							(end -0.1778 0.2794)
						)
						(arc
							(start 0.1778 0.2794)
							(mid 0.249642 0.249642)
							(end 0.2794 0.1778)
						)
						(arc
							(start 0.2794 -0.1778)
							(mid 0.249642 -0.249642)
							(end 0.1778 -0.2794)
						)
					)
					(width 0)
					(fill yes)
				)
			)
		)
		(pad "2" smd custom
			(at 0 0.4445 90)
			(size 0.1397 0.1397)
			(layers "F.Cu" "F.Mask" "F.Paste")
			(net "COMP_FAST_THROTTLE_N")
			(options
				(clearance outline)
				(anchor circle)
			)
			(primitives
				(gr_poly
					(pts
						(arc
							(start -0.1778 -0.2794)
							(mid -0.249642 -0.249642)
							(end -0.2794 -0.1778)
						)
						(arc
							(start -0.2794 0.1778)
							(mid -0.249642 0.249642)
							(end -0.1778 0.2794)
						)
						(arc
							(start 0.1778 0.2794)
							(mid 0.249642 0.249642)
							(end 0.2794 0.1778)
						)
						(arc
							(start 0.2794 -0.1778)
							(mid 0.249642 -0.249642)
							(end 0.1778 -0.2794)
						)
					)
					(width 0)
					(fill yes)
				)
			)
		)
	)
	(footprint ""
		(layer "F.Cu")
		(at 56.7436 -162.4838)
		(property "Reference" "R402"
			(at 0 0 0)
			(layer "F.SilkS")
			(hide yes)
			(effects
				(font
					(size 1.27 1.27)
				)
			)
		)
		(property "Value" "330R2F-GP"
			(at 0.064008 -3.993896 0)
			(unlocked yes)
			(layer "F.Fab")
			(hide yes)
			(effects
				(font
					(size 1.016 1.016)
					(thickness 0.1524)
				)
			)
		)
		(property "Device Type" "R402H16"
			(at 0.064008 -5.517896 0)
			(unlocked yes)
			(layer "F.Fab")
			(hide yes)
			(effects
				(font
					(size 1.016 1.016)
					(thickness 0.1524)
				)
			)
		)
		(duplicate_pad_numbers_are_jumpers no)
		(fp_line
			(start -0.508 -0.9398)
			(end -0.508 0.9398)
			(stroke
				(width 0.1524)
				(type default)
			)
			(layer "F.SilkS")
		)
		(fp_line
			(start 0.508 -0.9398)
			(end -0.508 -0.9398)
			(stroke
				(width 0.1524)
				(type default)
			)
			(layer "F.SilkS")
		)
		(fp_rect
			(start -0.508 0.9398)
			(end 0.508 -0.9398)
			(stroke
				(width 0)
				(type default)
			)
			(fill no)
			(layer "F.CrtYd")
		)
		(fp_rect
			(start -0.508 0.9398)
			(end 0.508 -0.9398)
			(stroke
				(width 0)
				(type default)
			)
			(fill no)
			(layer "F.Fab")
		)
		(pad "1" smd custom
			(at 0 -0.4445)
			(size 0.1397 0.1397)
			(layers "F.Cu" "F.Mask" "F.Paste")
			(net "P1V8_STBY")
			(options
				(clearance outline)
				(anchor circle)
			)
			(primitives
				(gr_poly
					(pts
						(arc
							(start -0.1778 -0.2794)
							(mid -0.249642 -0.249642)
							(end -0.2794 -0.1778)
						)
						(arc
							(start -0.2794 0.1778)
							(mid -0.249642 0.249642)
							(end -0.1778 0.2794)
						)
						(arc
							(start 0.1778 0.2794)
							(mid 0.249642 0.249642)
							(end 0.2794 0.1778)
						)
						(arc
							(start 0.2794 -0.1778)
							(mid 0.249642 -0.249642)
							(end 0.1778 -0.2794)
						)
					)
					(width 0)
					(fill yes)
				)
			)
		)
		(pad "2" smd custom
			(at 0 0.4445)
			(size 0.1397 0.1397)
			(layers "F.Cu" "F.Mask" "F.Paste")
			(net "ADC_P1V8_STBY")
			(options
				(clearance outline)
				(anchor circle)
			)
			(primitives
				(gr_poly
					(pts
						(arc
							(start -0.1778 -0.2794)
							(mid -0.249642 -0.249642)
							(end -0.2794 -0.1778)
						)
						(arc
							(start -0.2794 0.1778)
							(mid -0.249642 0.249642)
							(end -0.1778 0.2794)
						)
						(arc
							(start 0.1778 0.2794)
							(mid 0.249642 0.249642)
							(end 0.2794 0.1778)
						)
						(arc
							(start 0.2794 -0.1778)
							(mid 0.249642 -0.249642)
							(end 0.1778 -0.2794)
						)
					)
					(width 0)
					(fill yes)
				)
			)
		)
	)
	(footprint ""
		(layer "F.Cu")
		(at 11.7094 -171.014136 180)
		(property "Reference" "R534"
			(at 0 0 180)
			(layer "F.SilkS")
			(hide yes)
			(effects
				(font
					(size 1.27 1.27)
				)
			)
		)
		(property "Value" "4K75R2F-1-GP"
			(at 0.064008 -3.993896 180)
			(unlocked yes)
			(layer "F.Fab")
			(hide yes)
			(effects
				(font
					(size 1.016 1.016)
					(thickness 0.1524)
				)
			)
		)
		(property "Device Type" "R402H16"
			(at 0.064008 -5.517896 180)
			(unlocked yes)
			(layer "F.Fab")
			(hide yes)
			(effects
				(font
					(size 1.016 1.016)
					(thickness 0.1524)
				)
			)
		)
		(duplicate_pad_numbers_are_jumpers no)
		(fp_line
			(start 0.508 -0.9398)
			(end -0.508 -0.9398)
			(stroke
				(width 0.1524)
				(type default)
			)
			(layer "F.SilkS")
		)
		(fp_line
			(start -0.508 -0.9398)
			(end -0.508 0.9398)
			(stroke
				(width 0.1524)
				(type default)
			)
			(layer "F.SilkS")
		)
		(fp_rect
			(start -0.508 0.9398)
			(end 0.508 -0.9398)
			(stroke
				(width 0)
				(type default)
			)
			(fill no)
			(layer "F.CrtYd")
		)
		(fp_rect
			(start -0.508 0.9398)
			(end 0.508 -0.9398)
			(stroke
				(width 0)
				(type default)
			)
			(fill no)
			(layer "F.Fab")
		)
		(pad "1" smd custom
			(at 0 -0.4445 180)
			(size 0.1397 0.1397)
			(layers "F.Cu" "F.Mask" "F.Paste")
			(net "P3V3_STBY")
			(options
				(clearance outline)
				(anchor circle)
			)
			(primitives
				(gr_poly
					(pts
						(arc
							(start -0.1778 -0.2794)
							(mid -0.249642 -0.249642)
							(end -0.2794 -0.1778)
						)
						(arc
							(start -0.2794 0.1778)
							(mid -0.249642 0.249642)
							(end -0.1778 0.2794)
						)
						(arc
							(start 0.1778 0.2794)
							(mid 0.249642 0.249642)
							(end 0.2794 0.1778)
						)
						(arc
							(start 0.2794 -0.1778)
							(mid 0.249642 -0.249642)
							(end 0.1778 -0.2794)
						)
					)
					(width 0)
					(fill yes)
				)
			)
		)
		(pad "2" smd custom
			(at 0 0.4445 180)
			(size 0.1397 0.1397)
			(layers "F.Cu" "F.Mask" "F.Paste")
			(net "TPS74801_P1V2_STBY_EN")
			(options
				(clearance outline)
				(anchor circle)
			)
			(primitives
				(gr_poly
					(pts
						(arc
							(start -0.1778 -0.2794)
							(mid -0.249642 -0.249642)
							(end -0.2794 -0.1778)
						)
						(arc
							(start -0.2794 0.1778)
							(mid -0.249642 0.249642)
							(end -0.1778 0.2794)
						)
						(arc
							(start 0.1778 0.2794)
							(mid 0.249642 0.249642)
							(end 0.2794 0.1778)
						)
						(arc
							(start 0.2794 -0.1778)
							(mid 0.249642 -0.249642)
							(end 0.1778 -0.2794)
						)
					)
					(width 0)
					(fill yes)
				)
			)
		)
	)
	(footprint ""
		(layer "F.Cu")
		(at 33.772348 -153.240994 -90)
		(property "Reference" "R319"
			(at 0 0 270)
			(layer "F.SilkS")
			(hide yes)
			(effects
				(font
					(size 1.27 1.27)
				)
			)
		)
		(property "Value" "0R2J-2-GP"
			(at 0.064008 -3.993896 270)
			(unlocked yes)
			(layer "F.Fab")
			(hide yes)
			(effects
				(font
					(size 1.016 1.016)
					(thickness 0.1524)
				)
			)
		)
		(property "Device Type" "R402H16"
			(at 0.064008 -5.517896 270)
			(unlocked yes)
			(layer "F.Fab")
			(hide yes)
			(effects
				(font
					(size 1.016 1.016)
					(thickness 0.1524)
				)
			)
		)
		(duplicate_pad_numbers_are_jumpers no)
		(fp_line
			(start -0.508 -0.9398)
			(end -0.508 0.9398)
			(stroke
				(width 0.1524)
				(type default)
			)
			(layer "F.SilkS")
		)
		(fp_line
			(start 0.508 -0.9398)
			(end -0.508 -0.9398)
			(stroke
				(width 0.1524)
				(type default)
			)
			(layer "F.SilkS")
		)
		(fp_rect
			(start -0.508 0.9398)
			(end 0.508 -0.9398)
			(stroke
				(width 0)
				(type default)
			)
			(fill no)
			(layer "F.CrtYd")
		)
		(fp_rect
			(start -0.508 0.9398)
			(end 0.508 -0.9398)
			(stroke
				(width 0)
				(type default)
			)
			(fill no)
			(layer "F.Fab")
		)
		(pad "1" smd custom
			(at 0 -0.4445 270)
			(size 0.1397 0.1397)
			(layers "F.Cu" "F.Mask" "F.Paste")
			(net "ENCL_FAULT_LED_R")
			(options
				(clearance outline)
				(anchor circle)
			)
			(primitives
				(gr_poly
					(pts
						(arc
							(start -0.1778 -0.2794)
							(mid -0.249642 -0.249642)
							(end -0.2794 -0.1778)
						)
						(arc
							(start -0.2794 0.1778)
							(mid -0.249642 0.249642)
							(end -0.1778 0.2794)
						)
						(arc
							(start 0.1778 0.2794)
							(mid 0.249642 0.249642)
							(end 0.2794 0.1778)
						)
						(arc
							(start 0.2794 -0.1778)
							(mid 0.249642 -0.249642)
							(end 0.1778 -0.2794)
						)
					)
					(width 0)
					(fill yes)
				)
			)
		)
		(pad "2" smd custom
			(at 0 0.4445 270)
			(size 0.1397 0.1397)
			(layers "F.Cu" "F.Mask" "F.Paste")
			(net "ENCL_FAULT_LED")
			(options
				(clearance outline)
				(anchor circle)
			)
			(primitives
				(gr_poly
					(pts
						(arc
							(start -0.1778 -0.2794)
							(mid -0.249642 -0.249642)
							(end -0.2794 -0.1778)
						)
						(arc
							(start -0.2794 0.1778)
							(mid -0.249642 0.249642)
							(end -0.1778 0.2794)
						)
						(arc
							(start 0.1778 0.2794)
							(mid 0.249642 0.249642)
							(end 0.2794 0.1778)
						)
						(arc
							(start 0.2794 -0.1778)
							(mid 0.249642 -0.249642)
							(end 0.1778 -0.2794)
						)
					)
					(width 0)
					(fill yes)
				)
			)
		)
	)
)
